(kicad_pcb
	(version 20260206)
	(generator "pcbnew")
	(generator_version "10.0")
	(general
		(thickness 1.6)
		(legacy_teardrops no)
	)
	(paper "A4")
	(title_block
		(title "03242023_DA0F0TMBIJ0_F0T_Motherboard_J_brd_V01_OCP.brd")
		(comment 1 "Grand Teton / footprints 3997-4002 of 6105")
	)
	(layers
		(0 "F.Cu" signal "TOP")
		(4 "In1.Cu" signal "GND")
		(6 "In2.Cu" signal "IN1")
		(8 "In3.Cu" signal "GND1")
		(10 "In4.Cu" signal "IN2")
		(12 "In5.Cu" signal "GND2")
		(14 "In6.Cu" signal "IN3")
		(16 "In7.Cu" signal "GND3")
		(18 "In8.Cu" signal "VCC")
		(20 "In9.Cu" signal "VCC1")
		(22 "In10.Cu" signal "GND4")
		(24 "In11.Cu" signal "IN4")
		(26 "In12.Cu" signal "GND5")
		(28 "In13.Cu" signal "IN5")
		(30 "In14.Cu" signal "GND6")
		(32 "In15.Cu" signal "IN6")
		(34 "In16.Cu" signal "GND7")
		(2 "B.Cu" signal "BOTTOM")
		(9 "F.Adhes" user "F.Adhesive")
		(11 "B.Adhes" user "B.Adhesive")
		(13 "F.Paste" user "Package Geometry/Pastemask Top")
		(15 "B.Paste" user "Package Geometry/Pastemask Bottom")
		(5 "F.SilkS" user "Ref Des/Silkscreen Top")
		(7 "B.SilkS" user "Ref Des/Silkscreen Bottom")
		(1 "F.Mask" user "Board Geometry/Soldermask Top")
		(3 "B.Mask" user "Board Geometry/Soldermask Bottom")
		(17 "Dwgs.User" user "User.Drawings")
		(19 "Cmts.User" user "User.Comments")
		(21 "Eco1.User" user "User.Eco1")
		(23 "Eco2.User" user "User.Eco2")
		(25 "Edge.Cuts" user "Board Geometry/Outline")
		(27 "Margin" user)
		(31 "F.CrtYd" user "Package Geometry/Place Bound Top")
		(29 "B.CrtYd" user "Package Geometry/Place Bound Bottom")
		(35 "F.Fab" user "Ref Des/Assembly Top")
		(33 "B.Fab" user "Ref Des/Assembly Bottom")
	)
	(footprint ""
		(layer "F.Cu")
		(at 109.580934 -394.15974 180)
		(property "Reference" "R3488"
			(at 0 0 180)
			(layer "F.SilkS")
			(hide yes)
			(effects
				(font
					(size 1.27 1.27)
				)
			)
		)
		(property "Value" ""
			(at 0 0 180)
			(layer "F.Fab")
			(effects
				(font
					(size 1.27 1.27)
				)
			)
		)
		(duplicate_pad_numbers_are_jumpers no)
		(fp_line
			(start 0.7874 0.4064)
			(end -0.7874 0.4064)
			(stroke
				(width 0.1524)
				(type default)
			)
			(layer "F.SilkS")
		)
		(fp_line
			(start 0.7874 -0.4064)
			(end 0.7874 0.4064)
			(stroke
				(width 0.1524)
				(type default)
			)
			(layer "F.SilkS")
		)
		(fp_line
			(start -0.7874 0.4064)
			(end -0.7874 -0.4064)
			(stroke
				(width 0.1524)
				(type default)
			)
			(layer "F.SilkS")
		)
		(fp_line
			(start -0.7874 -0.4064)
			(end 0.7874 -0.4064)
			(stroke
				(width 0.1524)
				(type default)
			)
			(layer "F.SilkS")
		)
		(fp_line
			(start 0.67945 0.3048)
			(end 0.120396 0.3048)
			(stroke
				(width 0.1)
				(type default)
			)
			(layer "F.Fab")
		)
		(fp_line
			(start 0.67945 -0.3048)
			(end 0.67945 0.3048)
			(stroke
				(width 0.1)
				(type default)
			)
			(layer "F.Fab")
		)
		(fp_line
			(start 0.12065 -0.2794)
			(end 0.12065 -0.3048)
			(stroke
				(width 0.1)
				(type default)
			)
			(layer "F.Fab")
		)
		(fp_line
			(start 0.12065 -0.3048)
			(end 0.67945 -0.3048)
			(stroke
				(width 0.1)
				(type default)
			)
			(layer "F.Fab")
		)
		(fp_line
			(start 0.120396 0.3048)
			(end 0.120396 0.2794)
			(stroke
				(width 0.1)
				(type default)
			)
			(layer "F.Fab")
		)
		(fp_line
			(start 0.120396 0.2794)
			(end -0.12065 0.2794)
			(stroke
				(width 0.1)
				(type default)
			)
			(layer "F.Fab")
		)
		(fp_line
			(start -0.12065 0.3048)
			(end -0.67945 0.3048)
			(stroke
				(width 0.1)
				(type default)
			)
			(layer "F.Fab")
		)
		(fp_line
			(start -0.12065 0.2794)
			(end -0.12065 0.3048)
			(stroke
				(width 0.1)
				(type default)
			)
			(layer "F.Fab")
		)
		(fp_line
			(start -0.12065 -0.2794)
			(end 0.12065 -0.2794)
			(stroke
				(width 0.1)
				(type default)
			)
			(layer "F.Fab")
		)
		(fp_line
			(start -0.12065 -0.305054)
			(end -0.12065 -0.2794)
			(stroke
				(width 0.1)
				(type default)
			)
			(layer "F.Fab")
		)
		(fp_line
			(start -0.67945 0.3048)
			(end -0.67945 -0.305054)
			(stroke
				(width 0.1)
				(type default)
			)
			(layer "F.Fab")
		)
		(fp_line
			(start -0.67945 -0.305054)
			(end -0.12065 -0.305054)
			(stroke
				(width 0.1)
				(type default)
			)
			(layer "F.Fab")
		)
		(pad "1" smd circle
			(at -0.40005 0 180)
			(size 0 0)
			(layers "F.Cu" "F.Mask" "F.Paste")
			(net "P3V3_AUX")
		)
		(pad "2" smd circle
			(at 0.40005 0 180)
			(size 0 0)
			(layers "F.Cu" "F.Mask" "F.Paste")
			(net "GPU_FPGA_EROT_RST_N")
		)
	)
	(footprint ""
		(layer "F.Cu")
		(at 16.51 -426.1358 -90)
		(property "Reference" "R4742"
			(at 0 0 270)
			(layer "F.SilkS")
			(hide yes)
			(effects
				(font
					(size 1.27 1.27)
				)
			)
		)
		(property "Value" ""
			(at 0 0 270)
			(layer "F.Fab")
			(effects
				(font
					(size 1.27 1.27)
				)
			)
		)
		(duplicate_pad_numbers_are_jumpers no)
		(fp_line
			(start -0.7874 0.4064)
			(end -0.7874 -0.4064)
			(stroke
				(width 0.1524)
				(type default)
			)
			(layer "F.SilkS")
		)
		(fp_line
			(start 0.7874 0.4064)
			(end -0.7874 0.4064)
			(stroke
				(width 0.1524)
				(type default)
			)
			(layer "F.SilkS")
		)
		(fp_line
			(start -0.7874 -0.4064)
			(end 0.7874 -0.4064)
			(stroke
				(width 0.1524)
				(type default)
			)
			(layer "F.SilkS")
		)
		(fp_line
			(start 0.7874 -0.4064)
			(end 0.7874 0.4064)
			(stroke
				(width 0.1524)
				(type default)
			)
			(layer "F.SilkS")
		)
		(fp_line
			(start -0.67945 0.3048)
			(end -0.67945 -0.305054)
			(stroke
				(width 0.1)
				(type default)
			)
			(layer "F.Fab")
		)
		(fp_line
			(start -0.12065 0.3048)
			(end -0.67945 0.3048)
			(stroke
				(width 0.1)
				(type default)
			)
			(layer "F.Fab")
		)
		(fp_line
			(start 0.120396 0.3048)
			(end 0.120396 0.2794)
			(stroke
				(width 0.1)
				(type default)
			)
			(layer "F.Fab")
		)
		(fp_line
			(start 0.67945 0.3048)
			(end 0.120396 0.3048)
			(stroke
				(width 0.1)
				(type default)
			)
			(layer "F.Fab")
		)
		(fp_line
			(start -0.12065 0.2794)
			(end -0.12065 0.3048)
			(stroke
				(width 0.1)
				(type default)
			)
			(layer "F.Fab")
		)
		(fp_line
			(start 0.120396 0.2794)
			(end -0.12065 0.2794)
			(stroke
				(width 0.1)
				(type default)
			)
			(layer "F.Fab")
		)
		(fp_line
			(start -0.12065 -0.2794)
			(end 0.12065 -0.2794)
			(stroke
				(width 0.1)
				(type default)
			)
			(layer "F.Fab")
		)
		(fp_line
			(start 0.12065 -0.2794)
			(end 0.12065 -0.3048)
			(stroke
				(width 0.1)
				(type default)
			)
			(layer "F.Fab")
		)
		(fp_line
			(start 0.12065 -0.3048)
			(end 0.67945 -0.3048)
			(stroke
				(width 0.1)
				(type default)
			)
			(layer "F.Fab")
		)
		(fp_line
			(start 0.67945 -0.3048)
			(end 0.67945 0.3048)
			(stroke
				(width 0.1)
				(type default)
			)
			(layer "F.Fab")
		)
		(fp_line
			(start -0.67945 -0.305054)
			(end -0.12065 -0.305054)
			(stroke
				(width 0.1)
				(type default)
			)
			(layer "F.Fab")
		)
		(fp_line
			(start -0.12065 -0.305054)
			(end -0.12065 -0.2794)
			(stroke
				(width 0.1)
				(type default)
			)
			(layer "F.Fab")
		)
		(pad "1" smd circle
			(at -0.40005 0 270)
			(size 0 0)
			(layers "F.Cu" "F.Mask" "F.Paste")
			(net "PRSNT_CABLE_GPU_A1_ISO_N")
		)
		(pad "2" smd circle
			(at 0.40005 0 270)
			(size 0 0)
			(layers "F.Cu" "F.Mask" "F.Paste")
			(net "PRSNT_CABLE_GPU_A1_ISO_R1_N")
		)
	)
	(footprint ""
		(layer "F.Cu")
		(at 164.64788 -105.755948)
		(property "Reference" "R2844"
			(at 0 0 0)
			(layer "F.SilkS")
			(hide yes)
			(effects
				(font
					(size 1.27 1.27)
				)
			)
		)
		(property "Value" ""
			(at 0 0 0)
			(layer "F.Fab")
			(effects
				(font
					(size 1.27 1.27)
				)
			)
		)
		(duplicate_pad_numbers_are_jumpers no)
		(fp_line
			(start -0.7874 -0.4064)
			(end 0.7874 -0.4064)
			(stroke
				(width 0.1524)
				(type default)
			)
			(layer "F.SilkS")
		)
		(fp_line
			(start -0.7874 0.4064)
			(end -0.7874 -0.4064)
			(stroke
				(width 0.1524)
				(type default)
			)
			(layer "F.SilkS")
		)
		(fp_line
			(start 0.7874 -0.4064)
			(end 0.7874 0.4064)
			(stroke
				(width 0.1524)
				(type default)
			)
			(layer "F.SilkS")
		)
		(fp_line
			(start 0.7874 0.4064)
			(end -0.7874 0.4064)
			(stroke
				(width 0.1524)
				(type default)
			)
			(layer "F.SilkS")
		)
		(fp_line
			(start -0.67945 -0.305054)
			(end -0.12065 -0.305054)
			(stroke
				(width 0.1)
				(type default)
			)
			(layer "F.Fab")
		)
		(fp_line
			(start -0.67945 0.3048)
			(end -0.67945 -0.305054)
			(stroke
				(width 0.1)
				(type default)
			)
			(layer "F.Fab")
		)
		(fp_line
			(start -0.12065 -0.305054)
			(end -0.12065 -0.2794)
			(stroke
				(width 0.1)
				(type default)
			)
			(layer "F.Fab")
		)
		(fp_line
			(start -0.12065 -0.2794)
			(end 0.12065 -0.2794)
			(stroke
				(width 0.1)
				(type default)
			)
			(layer "F.Fab")
		)
		(fp_line
			(start -0.12065 0.2794)
			(end -0.12065 0.3048)
			(stroke
				(width 0.1)
				(type default)
			)
			(layer "F.Fab")
		)
		(fp_line
			(start -0.12065 0.3048)
			(end -0.67945 0.3048)
			(stroke
				(width 0.1)
				(type default)
			)
			(layer "F.Fab")
		)
		(fp_line
			(start 0.120396 0.2794)
			(end -0.12065 0.2794)
			(stroke
				(width 0.1)
				(type default)
			)
			(layer "F.Fab")
		)
		(fp_line
			(start 0.120396 0.3048)
			(end 0.120396 0.2794)
			(stroke
				(width 0.1)
				(type default)
			)
			(layer "F.Fab")
		)
		(fp_line
			(start 0.12065 -0.3048)
			(end 0.67945 -0.3048)
			(stroke
				(width 0.1)
				(type default)
			)
			(layer "F.Fab")
		)
		(fp_line
			(start 0.12065 -0.2794)
			(end 0.12065 -0.3048)
			(stroke
				(width 0.1)
				(type default)
			)
			(layer "F.Fab")
		)
		(fp_line
			(start 0.67945 -0.3048)
			(end 0.67945 0.3048)
			(stroke
				(width 0.1)
				(type default)
			)
			(layer "F.Fab")
		)
		(fp_line
			(start 0.67945 0.3048)
			(end 0.120396 0.3048)
			(stroke
				(width 0.1)
				(type default)
			)
			(layer "F.Fab")
		)
		(pad "1" smd circle
			(at -0.40005 0)
			(size 0 0)
			(layers "F.Cu" "F.Mask" "F.Paste")
			(net "FM_SWB_BIC_READY_ISO_N")
		)
		(pad "2" smd circle
			(at 0.40005 0)
			(size 0 0)
			(layers "F.Cu" "F.Mask" "F.Paste")
			(net "FM_SWB_BIC_READY_ISO_R_N")
		)
	)
	(footprint ""
		(layer "F.Cu")
		(at 108.05668 -59.070748)
		(property "Reference" "C1289"
			(at 0 0 0)
			(layer "F.SilkS")
			(hide yes)
			(effects
				(font
					(size 1.27 1.27)
				)
			)
		)
		(property "Value" ""
			(at 0 0 0)
			(layer "F.Fab")
			(effects
				(font
					(size 1.27 1.27)
				)
			)
		)
		(duplicate_pad_numbers_are_jumpers no)
		(fp_line
			(start -0.7874 -0.4064)
			(end 0.7874 -0.4064)
			(stroke
				(width 0.1524)
				(type default)
			)
			(layer "F.SilkS")
		)
		(fp_line
			(start -0.7874 0.4064)
			(end -0.7874 -0.4064)
			(stroke
				(width 0.1524)
				(type default)
			)
			(layer "F.SilkS")
		)
		(fp_line
			(start 0.7874 -0.4064)
			(end 0.7874 0.4064)
			(stroke
				(width 0.1524)
				(type default)
			)
			(layer "F.SilkS")
		)
		(fp_line
			(start 0.7874 0.4064)
			(end -0.7874 0.4064)
			(stroke
				(width 0.1524)
				(type default)
			)
			(layer "F.SilkS")
		)
		(fp_line
			(start -0.67945 -0.305054)
			(end -0.12065 -0.305054)
			(stroke
				(width 0.1)
				(type default)
			)
			(layer "F.Fab")
		)
		(fp_line
			(start -0.67945 0.3048)
			(end -0.67945 -0.305054)
			(stroke
				(width 0.1)
				(type default)
			)
			(layer "F.Fab")
		)
		(fp_line
			(start -0.12065 -0.305054)
			(end -0.12065 -0.2794)
			(stroke
				(width 0.1)
				(type default)
			)
			(layer "F.Fab")
		)
		(fp_line
			(start -0.12065 -0.2794)
			(end 0.12065 -0.2794)
			(stroke
				(width 0.1)
				(type default)
			)
			(layer "F.Fab")
		)
		(fp_line
			(start -0.12065 0.2794)
			(end -0.12065 0.3048)
			(stroke
				(width 0.1)
				(type default)
			)
			(layer "F.Fab")
		)
		(fp_line
			(start -0.12065 0.3048)
			(end -0.67945 0.3048)
			(stroke
				(width 0.1)
				(type default)
			)
			(layer "F.Fab")
		)
		(fp_line
			(start 0.120396 0.2794)
			(end -0.12065 0.2794)
			(stroke
				(width 0.1)
				(type default)
			)
			(layer "F.Fab")
		)
		(fp_line
			(start 0.120396 0.3048)
			(end 0.120396 0.2794)
			(stroke
				(width 0.1)
				(type default)
			)
			(layer "F.Fab")
		)
		(fp_line
			(start 0.12065 -0.3048)
			(end 0.67945 -0.3048)
			(stroke
				(width 0.1)
				(type default)
			)
			(layer "F.Fab")
		)
		(fp_line
			(start 0.12065 -0.2794)
			(end 0.12065 -0.3048)
			(stroke
				(width 0.1)
				(type default)
			)
			(layer "F.Fab")
		)
		(fp_line
			(start 0.67945 -0.3048)
			(end 0.67945 0.3048)
			(stroke
				(width 0.1)
				(type default)
			)
			(layer "F.Fab")
		)
		(fp_line
			(start 0.67945 0.3048)
			(end 0.120396 0.3048)
			(stroke
				(width 0.1)
				(type default)
			)
			(layer "F.Fab")
		)
		(pad "1" smd circle
			(at -0.40005 0)
			(size 0 0)
			(layers "F.Cu" "F.Mask" "F.Paste")
			(net "P3V3_AUX")
		)
		(pad "2" smd circle
			(at 0.40005 0)
			(size 0 0)
			(layers "F.Cu" "F.Mask" "F.Paste")
			(net "GND")
		)
	)
	(footprint ""
		(layer "F.Cu")
		(at 308.508654 -13.68044 180)
		(property "Reference" "C1663"
			(at 0 0 180)
			(layer "F.SilkS")
			(hide yes)
			(effects
				(font
					(size 1.27 1.27)
				)
			)
		)
		(property "Value" ""
			(at 0 0 180)
			(layer "F.Fab")
			(effects
				(font
					(size 1.27 1.27)
				)
			)
		)
		(duplicate_pad_numbers_are_jumpers no)
		(fp_line
			(start 0.7874 0.4064)
			(end -0.7874 0.4064)
			(stroke
				(width 0.1524)
				(type default)
			)
			(layer "F.SilkS")
		)
		(fp_line
			(start 0.7874 -0.4064)
			(end 0.7874 0.4064)
			(stroke
				(width 0.1524)
				(type default)
			)
			(layer "F.SilkS")
		)
		(fp_line
			(start -0.7874 0.4064)
			(end -0.7874 -0.4064)
			(stroke
				(width 0.1524)
				(type default)
			)
			(layer "F.SilkS")
		)
		(fp_line
			(start -0.7874 -0.4064)
			(end 0.7874 -0.4064)
			(stroke
				(width 0.1524)
				(type default)
			)
			(layer "F.SilkS")
		)
		(fp_line
			(start 0.67945 0.3048)
			(end 0.120396 0.3048)
			(stroke
				(width 0.1)
				(type default)
			)
			(layer "F.Fab")
		)
		(fp_line
			(start 0.67945 -0.3048)
			(end 0.67945 0.3048)
			(stroke
				(width 0.1)
				(type default)
			)
			(layer "F.Fab")
		)
		(fp_line
			(start 0.12065 -0.2794)
			(end 0.12065 -0.3048)
			(stroke
				(width 0.1)
				(type default)
			)
			(layer "F.Fab")
		)
		(fp_line
			(start 0.12065 -0.3048)
			(end 0.67945 -0.3048)
			(stroke
				(width 0.1)
				(type default)
			)
			(layer "F.Fab")
		)
		(fp_line
			(start 0.120396 0.3048)
			(end 0.120396 0.2794)
			(stroke
				(width 0.1)
				(type default)
			)
			(layer "F.Fab")
		)
		(fp_line
			(start 0.120396 0.2794)
			(end -0.12065 0.2794)
			(stroke
				(width 0.1)
				(type default)
			)
			(layer "F.Fab")
		)
		(fp_line
			(start -0.12065 0.3048)
			(end -0.67945 0.3048)
			(stroke
				(width 0.1)
				(type default)
			)
			(layer "F.Fab")
		)
		(fp_line
			(start -0.12065 0.2794)
			(end -0.12065 0.3048)
			(stroke
				(width 0.1)
				(type default)
			)
			(layer "F.Fab")
		)
		(fp_line
			(start -0.12065 -0.2794)
			(end 0.12065 -0.2794)
			(stroke
				(width 0.1)
				(type default)
			)
			(layer "F.Fab")
		)
		(fp_line
			(start -0.12065 -0.305054)
			(end -0.12065 -0.2794)
			(stroke
				(width 0.1)
				(type default)
			)
			(layer "F.Fab")
		)
		(fp_line
			(start -0.67945 0.3048)
			(end -0.67945 -0.305054)
			(stroke
				(width 0.1)
				(type default)
			)
			(layer "F.Fab")
		)
		(fp_line
			(start -0.67945 -0.305054)
			(end -0.12065 -0.305054)
			(stroke
				(width 0.1)
				(type default)
			)
			(layer "F.Fab")
		)
		(pad "1" smd circle
			(at -0.40005 0 180)
			(size 0 0)
			(layers "F.Cu" "F.Mask" "F.Paste")
			(net "P3V3_AUX")
		)
		(pad "2" smd circle
			(at 0.40005 0 180)
			(size 0 0)
			(layers "F.Cu" "F.Mask" "F.Paste")
			(net "GND")
		)
	)
	(footprint ""
		(layer "F.Cu")
		(at 193.60388 -99.875848)
		(property "Reference" "R700"
			(at 0 0 0)
			(layer "F.SilkS")
			(hide yes)
			(effects
				(font
					(size 1.27 1.27)
				)
			)
		)
		(property "Value" ""
			(at 0 0 0)
			(layer "F.Fab")
			(effects
				(font
					(size 1.27 1.27)
				)
			)
		)
		(duplicate_pad_numbers_are_jumpers no)
		(fp_line
			(start -0.7874 -0.4064)
			(end 0.7874 -0.4064)
			(stroke
				(width 0.1524)
				(type default)
			)
			(layer "F.SilkS")
		)
		(fp_line
			(start -0.7874 0.4064)
			(end -0.7874 -0.4064)
			(stroke
				(width 0.1524)
				(type default)
			)
			(layer "F.SilkS")
		)
		(fp_line
			(start 0.7874 -0.4064)
			(end 0.7874 0.4064)
			(stroke
				(width 0.1524)
				(type default)
			)
			(layer "F.SilkS")
		)
		(fp_line
			(start 0.7874 0.4064)
			(end -0.7874 0.4064)
			(stroke
				(width 0.1524)
				(type default)
			)
			(layer "F.SilkS")
		)
		(fp_line
			(start -0.67945 -0.305054)
			(end -0.12065 -0.305054)
			(stroke
				(width 0.1)
				(type default)
			)
			(layer "F.Fab")
		)
		(fp_line
			(start -0.67945 0.3048)
			(end -0.67945 -0.305054)
			(stroke
				(width 0.1)
				(type default)
			)
			(layer "F.Fab")
		)
		(fp_line
			(start -0.12065 -0.305054)
			(end -0.12065 -0.2794)
			(stroke
				(width 0.1)
				(type default)
			)
			(layer "F.Fab")
		)
		(fp_line
			(start -0.12065 -0.2794)
			(end 0.12065 -0.2794)
			(stroke
				(width 0.1)
				(type default)
			)
			(layer "F.Fab")
		)
		(fp_line
			(start -0.12065 0.2794)
			(end -0.12065 0.3048)
			(stroke
				(width 0.1)
				(type default)
			)
			(layer "F.Fab")
		)
		(fp_line
			(start -0.12065 0.3048)
			(end -0.67945 0.3048)
			(stroke
				(width 0.1)
				(type default)
			)
			(layer "F.Fab")
		)
		(fp_line
			(start 0.120396 0.2794)
			(end -0.12065 0.2794)
			(stroke
				(width 0.1)
				(type default)
			)
			(layer "F.Fab")
		)
		(fp_line
			(start 0.120396 0.3048)
			(end 0.120396 0.2794)
			(stroke
				(width 0.1)
				(type default)
			)
			(layer "F.Fab")
		)
		(fp_line
			(start 0.12065 -0.3048)
			(end 0.67945 -0.3048)
			(stroke
				(width 0.1)
				(type default)
			)
			(layer "F.Fab")
		)
		(fp_line
			(start 0.12065 -0.2794)
			(end 0.12065 -0.3048)
			(stroke
				(width 0.1)
				(type default)
			)
			(layer "F.Fab")
		)
		(fp_line
			(start 0.67945 -0.3048)
			(end 0.67945 0.3048)
			(stroke
				(width 0.1)
				(type default)
			)
			(layer "F.Fab")
		)
		(fp_line
			(start 0.67945 0.3048)
			(end 0.120396 0.3048)
			(stroke
				(width 0.1)
				(type default)
			)
			(layer "F.Fab")
		)
		(pad "1" smd circle
			(at -0.40005 0)
			(size 0 0)
			(layers "F.Cu" "F.Mask" "F.Paste")
			(net "FM_ADR_ACK_R")
		)
		(pad "2" smd circle
			(at 0.40005 0)
			(size 0 0)
			(layers "F.Cu" "F.Mask" "F.Paste")
			(net "FM_ADR_ACK")
		)
	)
)
